(kicad_pcb
	(version 20260206)
	(generator "pcbnew")
	(generator_version "10.0")
	(general
		(thickness 1.6)
		(legacy_teardrops no)
	)
	(paper "A4")
	(title_block
		(title "Wiwynn_Tioga_Pass_MB.brd")
		(comment 1 "Tioga Pass / footprints 1812-1819 of 4770")
	)
	(layers
		(0 "F.Cu" signal "TOP")
		(4 "In1.Cu" signal "L2GND")
		(6 "In2.Cu" signal "L3")
		(8 "In3.Cu" signal "L4GND")
		(10 "In4.Cu" signal "L5")
		(12 "In5.Cu" signal "L6GND")
		(14 "In6.Cu" signal "L7VCC")
		(16 "In7.Cu" signal "L8VCC")
		(18 "In8.Cu" signal "L9GND")
		(20 "In9.Cu" signal "L10")
		(22 "In10.Cu" signal "L11GND")
		(24 "In11.Cu" signal "L12")
		(26 "In12.Cu" signal "L13GND")
		(2 "B.Cu" signal "BOTTOM")
		(9 "F.Adhes" user "F.Adhesive")
		(11 "B.Adhes" user "B.Adhesive")
		(13 "F.Paste" user "Package Geometry/Pastemask Top")
		(15 "B.Paste" user "Package Geometry/Pastemask Bottom")
		(5 "F.SilkS" user "Ref Des/Silkscreen Top")
		(7 "B.SilkS" user "Ref Des/Silkscreen Bottom")
		(1 "F.Mask" user "Board Geometry/Soldermask Top")
		(3 "B.Mask" user "Board Geometry/Soldermask Bottom")
		(17 "Dwgs.User" user "User.Drawings")
		(19 "Cmts.User" user "User.Comments")
		(21 "Eco1.User" user "User.Eco1")
		(23 "Eco2.User" user "User.Eco2")
		(25 "Edge.Cuts" user "Board Geometry/Outline")
		(27 "Margin" user)
		(31 "F.CrtYd" user "Package Geometry/Place Bound Top")
		(29 "B.CrtYd" user "Package Geometry/Place Bound Bottom")
		(35 "F.Fab" user "Ref Des/Assembly Top")
		(33 "B.Fab" user "Ref Des/Assembly Bottom")
	)
	(footprint ""
		(layer "F.Cu")
		(at 268.401038 -68.365116 180)
		(property "Reference" "C5D58"
			(at 0 0 180)
			(layer "F.SilkS")
			(hide yes)
			(effects
				(font
					(size 1.27 1.27)
				)
			)
		)
		(property "Value" ""
			(at 0 0 180)
			(layer "F.Fab")
			(effects
				(font
					(size 1.27 1.27)
				)
			)
		)
		(duplicate_pad_numbers_are_jumpers no)
		(fp_poly
			(pts
				(xy -0.4953 -0.2032) (xy 0.4953 -0.2032) (xy 0.4953 1.6002) (xy -0.4953 1.6002)
			)
			(stroke
				(width 0)
				(type default)
			)
			(fill no)
			(layer "F.CrtYd")
		)
		(fp_line
			(start 0.4953 1.6002)
			(end -0.4953 1.6002)
			(stroke
				(width 0.1)
				(type default)
			)
			(layer "F.Fab")
		)
		(fp_line
			(start 0.4953 -0.2032)
			(end 0.4953 1.6002)
			(stroke
				(width 0.1)
				(type default)
			)
			(layer "F.Fab")
		)
		(fp_line
			(start -0.4953 1.6002)
			(end -0.4953 -0.2032)
			(stroke
				(width 0.1)
				(type default)
			)
			(layer "F.Fab")
		)
		(fp_line
			(start -0.4953 -0.2032)
			(end 0.4953 -0.2032)
			(stroke
				(width 0.1)
				(type default)
			)
			(layer "F.Fab")
		)
		(pad "1" smd rect
			(at 0 0 180)
			(size 0.762 0.889)
			(layers "F.Cu" "F.Mask" "F.Paste")
			(net "PVDDQ_ABC")
		)
		(pad "2" smd rect
			(at 0 1.397 180)
			(size 0.762 0.889)
			(layers "F.Cu" "F.Mask" "F.Paste")
			(net "GND")
		)
		(zone
			(layer "F.Cu")
			(hatch none 0.5)
			(connect_pads
				(clearance 0)
			)
			(min_thickness 0.25)
			(keepout
				(tracks not_allowed)
				(vias allowed)
				(pads allowed)
				(copperpour not_allowed)
				(footprints allowed)
			)
			(placement
				(enabled no)
				(sheetname "")
			)
			(fill
				(thermal_gap 0.5)
				(thermal_bridge_width 0.5)
				(island_removal_mode 0)
			)
			(polygon
				(pts
					(xy 268.782038 -68.809616) (xy 268.020038 -68.809616) (xy 268.020038 -69.317616) (xy 268.782038 -69.317616)
				)
			)
		)
	)
	(footprint ""
		(layer "F.Cu")
		(at 96.746568 -23.241 180)
		(property "Reference" "C2F2"
			(at 0 0 180)
			(layer "F.SilkS")
			(hide yes)
			(effects
				(font
					(size 1.27 1.27)
				)
			)
		)
		(property "Value" ""
			(at 0 0 180)
			(layer "F.Fab")
			(effects
				(font
					(size 1.27 1.27)
				)
			)
		)
		(duplicate_pad_numbers_are_jumpers no)
		(fp_rect
			(start -0.500126 1.598422)
			(end 0.500126 -0.201422)
			(stroke
				(width 0)
				(type default)
			)
			(fill no)
			(layer "F.CrtYd")
		)
		(fp_line
			(start 0.500126 1.598422)
			(end -0.500126 1.598422)
			(stroke
				(width 0.1)
				(type default)
			)
			(layer "F.Fab")
		)
		(fp_line
			(start 0.500126 -0.201422)
			(end 0.500126 1.598422)
			(stroke
				(width 0.1)
				(type default)
			)
			(layer "F.Fab")
		)
		(fp_line
			(start -0.500126 1.598422)
			(end -0.500126 -0.201422)
			(stroke
				(width 0.1)
				(type default)
			)
			(layer "F.Fab")
		)
		(fp_line
			(start -0.500126 -0.201422)
			(end 0.500126 -0.201422)
			(stroke
				(width 0.1)
				(type default)
			)
			(layer "F.Fab")
		)
		(pad "1" smd rect
			(at 0 0 90)
			(size 0.889 0.9906)
			(layers "F.Cu" "F.Mask" "F.Paste")
			(net "PVTT_GHJ")
		)
		(pad "2" smd rect
			(at 0 1.397 90)
			(size 0.889 0.9906)
			(layers "F.Cu" "F.Mask" "F.Paste")
			(net "GND")
		)
		(zone
			(layer "F.Cu")
			(hatch none 0.5)
			(connect_pads
				(clearance 0)
			)
			(min_thickness 0.25)
			(keepout
				(tracks not_allowed)
				(vias allowed)
				(pads allowed)
				(copperpour not_allowed)
				(footprints allowed)
			)
			(placement
				(enabled no)
				(sheetname "")
			)
			(fill
				(thermal_gap 0.5)
				(thermal_bridge_width 0.5)
				(island_removal_mode 0)
			)
			(polygon
				(pts
					(xy 97.241868 -24.1935) (xy 96.251268 -24.1935) (xy 96.251268 -23.6855) (xy 97.241868 -23.6855)
				)
			)
		)
		(zone
			(layer "F.Cu")
			(hatch none 0.5)
			(connect_pads
				(clearance 0)
			)
			(min_thickness 0.25)
			(keepout
				(tracks allowed)
				(vias not_allowed)
				(pads allowed)
				(copperpour not_allowed)
				(footprints allowed)
			)
			(placement
				(enabled no)
				(sheetname "")
			)
			(fill
				(thermal_gap 0.5)
				(thermal_bridge_width 0.5)
				(island_removal_mode 0)
			)
			(polygon
				(pts
					(xy 97.241868 -24.1935) (xy 96.251268 -24.1935) (xy 96.251268 -23.6855) (xy 97.241868 -23.6855)
				)
			)
		)
	)
	(footprint ""
		(layer "F.Cu")
		(at 445.1985 -1.143 90)
		(property "Reference" "R7D30"
			(at 0 0 90)
			(layer "F.SilkS")
			(hide yes)
			(effects
				(font
					(size 1.27 1.27)
				)
			)
		)
		(property "Value" ""
			(at 0 0 90)
			(layer "F.Fab")
			(effects
				(font
					(size 1.27 1.27)
				)
			)
		)
		(duplicate_pad_numbers_are_jumpers no)
		(fp_poly
			(pts
				(xy -0.2794 -0.1016) (xy 0.2794 -0.1016) (xy 0.2794 0.9906) (xy -0.2794 0.9906)
			)
			(stroke
				(width 0)
				(type default)
			)
			(fill no)
			(layer "F.CrtYd")
		)
		(fp_line
			(start 0.2794 -0.1016)
			(end -0.2794 -0.1016)
			(stroke
				(width 0.1)
				(type default)
			)
			(layer "F.Fab")
		)
		(fp_line
			(start -0.2794 -0.1016)
			(end -0.2794 0.9906)
			(stroke
				(width 0.1)
				(type default)
			)
			(layer "F.Fab")
		)
		(fp_line
			(start 0.2794 0.9906)
			(end 0.2794 -0.1016)
			(stroke
				(width 0.1)
				(type default)
			)
			(layer "F.Fab")
		)
		(fp_line
			(start -0.2794 0.9906)
			(end 0.2794 0.9906)
			(stroke
				(width 0.1)
				(type default)
			)
			(layer "F.Fab")
		)
		(pad "1" smd rect
			(at 0 0 90)
			(size 0.508 0.508)
			(layers "F.Cu" "F.Mask" "F.Paste")
			(net "P3V3_STBY")
		)
		(pad "2" smd rect
			(at 0 0.889 90)
			(size 0.508 0.508)
			(layers "F.Cu" "F.Mask" "F.Paste")
			(net "FM_CPLD_UART_CH_LOCK_N")
		)
		(zone
			(layer "F.Cu")
			(hatch none 0.5)
			(connect_pads
				(clearance 0)
			)
			(min_thickness 0.25)
			(keepout
				(tracks allowed)
				(vias not_allowed)
				(pads allowed)
				(copperpour not_allowed)
				(footprints allowed)
			)
			(placement
				(enabled no)
				(sheetname "")
			)
			(fill
				(thermal_gap 0.5)
				(thermal_bridge_width 0.5)
				(island_removal_mode 0)
			)
			(polygon
				(pts
					(xy 445.4525 -0.889) (xy 445.4525 -1.397) (xy 445.8335 -1.397) (xy 445.8335 -0.889)
				)
			)
		)
		(zone
			(layer "F.Cu")
			(hatch none 0.5)
			(connect_pads
				(clearance 0)
			)
			(min_thickness 0.25)
			(keepout
				(tracks not_allowed)
				(vias allowed)
				(pads allowed)
				(copperpour not_allowed)
				(footprints allowed)
			)
			(placement
				(enabled no)
				(sheetname "")
			)
			(fill
				(thermal_gap 0.5)
				(thermal_bridge_width 0.5)
				(island_removal_mode 0)
			)
			(polygon
				(pts
					(xy 445.8335 -0.889) (xy 445.8335 -1.397) (xy 445.4525 -1.397) (xy 445.4525 -0.889)
				)
			)
		)
	)
	(footprint ""
		(layer "F.Cu")
		(at 40.036496 -89.416382)
		(property "Reference" "L1C2"
			(at 3.378708 -4.251706 0)
			(unlocked yes)
			(layer "F.SilkS")
			(effects
				(font
					(size 0.4064 0.254)
					(thickness 0.1524)
				)
			)
		)
		(property "Value" ""
			(at 0 0 0)
			(layer "F.Fab")
			(effects
				(font
					(size 1.27 1.27)
				)
			)
		)
		(duplicate_pad_numbers_are_jumpers no)
		(fp_line
			(start -1.1303 -3.199892)
			(end 8.3693 -3.199892)
			(stroke
				(width 0.1524)
				(type default)
			)
			(layer "F.SilkS")
		)
		(fp_line
			(start -1.1303 -1.6637)
			(end -1.1303 -3.199892)
			(stroke
				(width 0.1524)
				(type default)
			)
			(layer "F.SilkS")
		)
		(fp_line
			(start -1.1303 3.199892)
			(end -1.1303 1.6637)
			(stroke
				(width 0.1524)
				(type default)
			)
			(layer "F.SilkS")
		)
		(fp_line
			(start 8.3693 -3.199892)
			(end 8.3693 -1.6637)
			(stroke
				(width 0.1524)
				(type default)
			)
			(layer "F.SilkS")
		)
		(fp_line
			(start 8.3693 1.6637)
			(end 8.3693 3.199892)
			(stroke
				(width 0.1524)
				(type default)
			)
			(layer "F.SilkS")
		)
		(fp_line
			(start 8.3693 3.199892)
			(end -1.1303 3.199892)
			(stroke
				(width 0.1524)
				(type default)
			)
			(layer "F.SilkS")
		)
		(fp_rect
			(start -1.1303 3.199892)
			(end 8.3693 -3.199892)
			(stroke
				(width 0)
				(type default)
			)
			(fill no)
			(layer "F.CrtYd")
		)
		(fp_line
			(start -1.1303 -3.199892)
			(end 8.3693 -3.199892)
			(stroke
				(width 0.1)
				(type default)
			)
			(layer "F.Fab")
		)
		(fp_line
			(start -1.1303 3.199892)
			(end -1.1303 -3.199892)
			(stroke
				(width 0.1)
				(type default)
			)
			(layer "F.Fab")
		)
		(fp_line
			(start 8.3693 -3.199892)
			(end 8.3693 3.199892)
			(stroke
				(width 0.1)
				(type default)
			)
			(layer "F.Fab")
		)
		(fp_line
			(start 8.3693 3.199892)
			(end -1.1303 3.199892)
			(stroke
				(width 0.1)
				(type default)
			)
			(layer "F.Fab")
		)
		(pad "1" smd rect
			(at 0 0)
			(size 3.683 2.667)
			(layers "F.Cu" "F.Mask" "F.Paste")
			(net "VR_PVCCIN_CPU1_PHASE5")
		)
		(pad "2" smd rect
			(at 7.239 0)
			(size 3.683 2.667)
			(layers "F.Cu" "F.Mask" "F.Paste")
			(net "PVCCIN_CPU1")
		)
	)
	(footprint ""
		(layer "F.Cu")
		(at 168.9608 -144.6276 90)
		(property "Reference" "C4A15"
			(at 0 0 90)
			(layer "F.SilkS")
			(hide yes)
			(effects
				(font
					(size 1.27 1.27)
				)
			)
		)
		(property "Value" ""
			(at 0 0 90)
			(layer "F.Fab")
			(effects
				(font
					(size 1.27 1.27)
				)
			)
		)
		(duplicate_pad_numbers_are_jumpers no)
		(fp_rect
			(start 0.4953 1.6002)
			(end -0.4953 -0.2032)
			(stroke
				(width 0)
				(type default)
			)
			(fill no)
			(layer "F.CrtYd")
		)
		(fp_line
			(start 0.4953 -0.2032)
			(end 0.4953 1.6002)
			(stroke
				(width 0.1)
				(type default)
			)
			(layer "F.Fab")
		)
		(fp_line
			(start -0.4953 -0.2032)
			(end 0.4953 -0.2032)
			(stroke
				(width 0.1)
				(type default)
			)
			(layer "F.Fab")
		)
		(fp_line
			(start 0.4953 1.6002)
			(end -0.4953 1.6002)
			(stroke
				(width 0.1)
				(type default)
			)
			(layer "F.Fab")
		)
		(fp_line
			(start -0.4953 1.6002)
			(end -0.4953 -0.2032)
			(stroke
				(width 0.1)
				(type default)
			)
			(layer "F.Fab")
		)
		(pad "1" smd rect
			(at 0 0 90)
			(size 0.762 0.889)
			(layers "F.Cu" "F.Mask" "F.Paste")
			(net "PVDDQ_KLM")
		)
		(pad "2" smd rect
			(at 0 1.397 90)
			(size 0.762 0.889)
			(layers "F.Cu" "F.Mask" "F.Paste")
			(net "GND")
		)
		(zone
			(layer "F.Cu")
			(hatch none 0.5)
			(connect_pads
				(clearance 0)
			)
			(min_thickness 0.25)
			(keepout
				(tracks not_allowed)
				(vias allowed)
				(pads allowed)
				(copperpour not_allowed)
				(footprints allowed)
			)
			(placement
				(enabled no)
				(sheetname "")
			)
			(fill
				(thermal_gap 0.5)
				(thermal_bridge_width 0.5)
				(island_removal_mode 0)
			)
			(polygon
				(pts
					(xy 169.9133 -145.0086) (xy 169.4053 -145.0086) (xy 169.4053 -144.2466) (xy 169.9133 -144.2466)
				)
			)
		)
	)
	(footprint ""
		(layer "F.Cu")
		(at 418.465 -18.7452)
		(property "Reference" "R1U8"
			(at 0 0 0)
			(layer "F.SilkS")
			(hide yes)
			(effects
				(font
					(size 1.27 1.27)
				)
			)
		)
		(property "Value" ""
			(at 0 0 0)
			(layer "F.Fab")
			(effects
				(font
					(size 1.27 1.27)
				)
			)
		)
		(duplicate_pad_numbers_are_jumpers no)
		(fp_poly
			(pts
				(xy -0.2794 -0.1016) (xy 0.2794 -0.1016) (xy 0.2794 0.9906) (xy -0.2794 0.9906)
			)
			(stroke
				(width 0)
				(type default)
			)
			(fill no)
			(layer "F.CrtYd")
		)
		(fp_line
			(start -0.2794 -0.1016)
			(end -0.2794 0.9906)
			(stroke
				(width 0.1)
				(type default)
			)
			(layer "F.Fab")
		)
		(fp_line
			(start -0.2794 0.9906)
			(end 0.2794 0.9906)
			(stroke
				(width 0.1)
				(type default)
			)
			(layer "F.Fab")
		)
		(fp_line
			(start 0.2794 -0.1016)
			(end -0.2794 -0.1016)
			(stroke
				(width 0.1)
				(type default)
			)
			(layer "F.Fab")
		)
		(fp_line
			(start 0.2794 0.9906)
			(end 0.2794 -0.1016)
			(stroke
				(width 0.1)
				(type default)
			)
			(layer "F.Fab")
		)
		(pad "1" smd rect
			(at 0 0)
			(size 0.508 0.508)
			(layers "F.Cu" "F.Mask" "F.Paste")
			(net "SMB_VR_STBY_LVC3_SDA_R")
		)
		(pad "2" smd rect
			(at 0 0.889)
			(size 0.508 0.508)
			(layers "F.Cu" "F.Mask" "F.Paste")
			(net "SMB_VR_STBY_LVC3_SDA")
		)
		(zone
			(layer "F.Cu")
			(hatch none 0.5)
			(connect_pads
				(clearance 0)
			)
			(min_thickness 0.25)
			(keepout
				(tracks allowed)
				(vias not_allowed)
				(pads allowed)
				(copperpour not_allowed)
				(footprints allowed)
			)
			(placement
				(enabled no)
				(sheetname "")
			)
			(fill
				(thermal_gap 0.5)
				(thermal_bridge_width 0.5)
				(island_removal_mode 0)
			)
			(polygon
				(pts
					(xy 418.211 -18.4912) (xy 418.719 -18.4912) (xy 418.719 -18.1102) (xy 418.211 -18.1102)
				)
			)
		)
		(zone
			(layer "F.Cu")
			(hatch none 0.5)
			(connect_pads
				(clearance 0)
			)
			(min_thickness 0.25)
			(keepout
				(tracks not_allowed)
				(vias allowed)
				(pads allowed)
				(copperpour not_allowed)
				(footprints allowed)
			)
			(placement
				(enabled no)
				(sheetname "")
			)
			(fill
				(thermal_gap 0.5)
				(thermal_bridge_width 0.5)
				(island_removal_mode 0)
			)
			(polygon
				(pts
					(xy 418.211 -18.1102) (xy 418.719 -18.1102) (xy 418.719 -18.4912) (xy 418.211 -18.4912)
				)
			)
		)
	)
	(footprint ""
		(layer "F.Cu")
		(at -3.556 -128.6002 90)
		(property "Reference" "R1B8"
			(at 0 0 90)
			(layer "F.SilkS")
			(hide yes)
			(effects
				(font
					(size 1.27 1.27)
				)
			)
		)
		(property "Value" ""
			(at 0 0 90)
			(layer "F.Fab")
			(effects
				(font
					(size 1.27 1.27)
				)
			)
		)
		(duplicate_pad_numbers_are_jumpers no)
		(fp_rect
			(start -0.2794 -0.1016)
			(end 0.2794 0.9906)
			(stroke
				(width 0)
				(type default)
			)
			(fill no)
			(layer "F.CrtYd")
		)
		(fp_line
			(start 0.2794 -0.1016)
			(end -0.2794 -0.1016)
			(stroke
				(width 0.1)
				(type default)
			)
			(layer "F.Fab")
		)
		(fp_line
			(start -0.2794 -0.1016)
			(end -0.2794 0.9906)
			(stroke
				(width 0.1)
				(type default)
			)
			(layer "F.Fab")
		)
		(fp_line
			(start 0.2794 0.9906)
			(end 0.2794 -0.1016)
			(stroke
				(width 0.1)
				(type default)
			)
			(layer "F.Fab")
		)
		(fp_line
			(start -0.2794 0.9906)
			(end 0.2794 0.9906)
			(stroke
				(width 0.1)
				(type default)
			)
			(layer "F.Fab")
		)
		(pad "1" smd rect
			(at 0 0 90)
			(size 0.508 0.508)
			(layers "F.Cu" "F.Mask" "F.Paste")
			(net "SVID_CLK1_CPU1_R")
		)
		(pad "2" smd rect
			(at 0 0.889 90)
			(size 0.508 0.508)
			(layers "F.Cu" "F.Mask" "F.Paste")
			(net "SVID_CLK_PVDDQ_KLM")
		)
		(zone
			(layer "F.Cu")
			(hatch none 0.5)
			(connect_pads
				(clearance 0)
			)
			(min_thickness 0.25)
			(keepout
				(tracks not_allowed)
				(vias allowed)
				(pads allowed)
				(copperpour not_allowed)
				(footprints allowed)
			)
			(placement
				(enabled no)
				(sheetname "")
			)
			(fill
				(thermal_gap 0.5)
				(thermal_bridge_width 0.5)
				(island_removal_mode 0)
			)
			(polygon
				(pts
					(xy -3.302 -128.3462) (xy -2.921 -128.3462) (xy -2.921 -128.8542) (xy -3.302 -128.8542)
				)
			)
		)
		(zone
			(layer "F.Cu")
			(hatch none 0.5)
			(connect_pads
				(clearance 0)
			)
			(min_thickness 0.25)
			(keepout
				(tracks allowed)
				(vias not_allowed)
				(pads allowed)
				(copperpour not_allowed)
				(footprints allowed)
			)
			(placement
				(enabled no)
				(sheetname "")
			)
			(fill
				(thermal_gap 0.5)
				(thermal_bridge_width 0.5)
				(island_removal_mode 0)
			)
			(polygon
				(pts
					(xy -3.302 -128.3462) (xy -2.921 -128.3462) (xy -2.921 -128.8542) (xy -3.302 -128.8542)
				)
			)
		)
	)
	(footprint ""
		(layer "F.Cu")
		(at 390.525 -71.0565 180)
		(property "Reference" "R7E14"
			(at 0 0 180)
			(layer "F.SilkS")
			(hide yes)
			(effects
				(font
					(size 1.27 1.27)
				)
			)
		)
		(property "Value" ""
			(at 0 0 180)
			(layer "F.Fab")
			(effects
				(font
					(size 1.27 1.27)
				)
			)
		)
		(duplicate_pad_numbers_are_jumpers no)
		(fp_poly
			(pts
				(xy -0.2794 -0.1016) (xy 0.2794 -0.1016) (xy 0.2794 0.9906) (xy -0.2794 0.9906)
			)
			(stroke
				(width 0)
				(type default)
			)
			(fill no)
			(layer "F.CrtYd")
		)
		(fp_line
			(start 0.2794 0.9906)
			(end 0.2794 -0.1016)
			(stroke
				(width 0.1)
				(type default)
			)
			(layer "F.Fab")
		)
		(fp_line
			(start 0.2794 -0.1016)
			(end -0.2794 -0.1016)
			(stroke
				(width 0.1)
				(type default)
			)
			(layer "F.Fab")
		)
		(fp_line
			(start -0.2794 0.9906)
			(end 0.2794 0.9906)
			(stroke
				(width 0.1)
				(type default)
			)
			(layer "F.Fab")
		)
		(fp_line
			(start -0.2794 -0.1016)
			(end -0.2794 0.9906)
			(stroke
				(width 0.1)
				(type default)
			)
			(layer "F.Fab")
		)
		(pad "1" smd rect
			(at 0 0 180)
			(size 0.508 0.508)
			(layers "F.Cu" "F.Mask" "F.Paste")
			(net "VR_P5V_STBY_RT")
		)
		(pad "2" smd rect
			(at 0 0.889 180)
			(size 0.508 0.508)
			(layers "F.Cu" "F.Mask" "F.Paste")
			(net "AGND_P5V_STBY")
		)
		(zone
			(layer "F.Cu")
			(hatch none 0.5)
			(connect_pads
				(clearance 0)
			)
			(min_thickness 0.25)
			(keepout
				(tracks not_allowed)
				(vias allowed)
				(pads allowed)
				(copperpour not_allowed)
				(footprints allowed)
			)
			(placement
				(enabled no)
				(sheetname "")
			)
			(fill
				(thermal_gap 0.5)
				(thermal_bridge_width 0.5)
				(island_removal_mode 0)
			)
			(polygon
				(pts
					(xy 390.779 -71.6915) (xy 390.271 -71.6915) (xy 390.271 -71.3105) (xy 390.779 -71.3105)
				)
			)
		)
		(zone
			(layer "F.Cu")
			(hatch none 0.5)
			(connect_pads
				(clearance 0)
			)
			(min_thickness 0.25)
			(keepout
				(tracks allowed)
				(vias not_allowed)
				(pads allowed)
				(copperpour not_allowed)
				(footprints allowed)
			)
			(placement
				(enabled no)
				(sheetname "")
			)
			(fill
				(thermal_gap 0.5)
				(thermal_bridge_width 0.5)
				(island_removal_mode 0)
			)
			(polygon
				(pts
					(xy 390.779 -71.3105) (xy 390.271 -71.3105) (xy 390.271 -71.6915) (xy 390.779 -71.6915)
				)
			)
		)
	)
)
